(kicad_pcb
	(version 20260206)
	(generator "pcbnew")
	(generator_version "10.0")
	(general
		(thickness 1.6)
		(legacy_teardrops no)
	)
	(paper "A4")
	(title_block
		(title "04192023_DAF0TMB3IC0_F0TG_MB_C_brd_V02_OCP.brd")
		(comment 1 "Grand Teton / footprints 5189-5195 of 8354")
	)
	(layers
		(0 "F.Cu" signal "TOP")
		(4 "In1.Cu" signal "GND")
		(6 "In2.Cu" signal "IN1")
		(8 "In3.Cu" signal "GND1")
		(10 "In4.Cu" signal "IN2")
		(12 "In5.Cu" signal "GND2")
		(14 "In6.Cu" signal "IN3")
		(16 "In7.Cu" signal "GND3")
		(18 "In8.Cu" signal "VCC")
		(20 "In9.Cu" signal "VCC1")
		(22 "In10.Cu" signal "GND4")
		(24 "In11.Cu" signal "IN4")
		(26 "In12.Cu" signal "GND5")
		(28 "In13.Cu" signal "IN5")
		(30 "In14.Cu" signal "GND6")
		(32 "In15.Cu" signal "IN6")
		(34 "In16.Cu" signal "GND7")
		(2 "B.Cu" signal "BOTTOM")
		(9 "F.Adhes" user "F.Adhesive")
		(11 "B.Adhes" user "B.Adhesive")
		(13 "F.Paste" user "Package Geometry/Pastemask Top")
		(15 "B.Paste" user "Package Geometry/Pastemask Bottom")
		(5 "F.SilkS" user "Ref Des/Silkscreen Top")
		(7 "B.SilkS" user "Ref Des/Silkscreen Bottom")
		(1 "F.Mask" user "Board Geometry/Soldermask Top")
		(3 "B.Mask" user "Board Geometry/Soldermask Bottom")
		(17 "Dwgs.User" user "User.Drawings")
		(19 "Cmts.User" user "User.Comments")
		(21 "Eco1.User" user "User.Eco1")
		(23 "Eco2.User" user "User.Eco2")
		(25 "Edge.Cuts" user "Board Geometry/Outline")
		(27 "Margin" user)
		(31 "F.CrtYd" user "Package Geometry/Place Bound Top")
		(29 "B.CrtYd" user "Package Geometry/Place Bound Bottom")
		(35 "F.Fab" user "Ref Des/Assembly Top")
		(33 "B.Fab" user "Ref Des/Assembly Bottom")
	)
	(footprint ""
		(layer "B.Cu")
		(at 416.218878 -398.942052 90)
		(property "Reference" "C981"
			(at 0 0 90)
			(layer "B.SilkS")
			(hide yes)
			(effects
				(font
					(size 1.27 1.27)
				)
				(justify mirror)
			)
		)
		(property "Value" ""
			(at 0 0 90)
			(layer "B.Fab")
			(effects
				(font
					(size 1.27 1.27)
				)
				(justify mirror)
			)
		)
		(duplicate_pad_numbers_are_jumpers no)
		(fp_line
			(start 0.7874 -0.4064)
			(end -0.7874 -0.4064)
			(stroke
				(width 0.1524)
				(type default)
			)
			(layer "B.SilkS")
		)
		(fp_line
			(start -0.7874 -0.4064)
			(end -0.7874 0.4064)
			(stroke
				(width 0.1524)
				(type default)
			)
			(layer "B.SilkS")
		)
		(fp_line
			(start 0.7874 0.4064)
			(end 0.7874 -0.4064)
			(stroke
				(width 0.1524)
				(type default)
			)
			(layer "B.SilkS")
		)
		(fp_line
			(start -0.7874 0.4064)
			(end 0.7874 0.4064)
			(stroke
				(width 0.1524)
				(type default)
			)
			(layer "B.SilkS")
		)
		(fp_line
			(start 0.67945 -0.305054)
			(end 0.12065 -0.305054)
			(stroke
				(width 0.1)
				(type default)
			)
			(layer "B.Fab")
		)
		(fp_line
			(start 0.12065 -0.305054)
			(end 0.12065 -0.2794)
			(stroke
				(width 0.1)
				(type default)
			)
			(layer "B.Fab")
		)
		(fp_line
			(start -0.12065 -0.3048)
			(end -0.67945 -0.3048)
			(stroke
				(width 0.1)
				(type default)
			)
			(layer "B.Fab")
		)
		(fp_line
			(start -0.67945 -0.3048)
			(end -0.67945 0.3048)
			(stroke
				(width 0.1)
				(type default)
			)
			(layer "B.Fab")
		)
		(fp_line
			(start 0.12065 -0.2794)
			(end -0.12065 -0.2794)
			(stroke
				(width 0.1)
				(type default)
			)
			(layer "B.Fab")
		)
		(fp_line
			(start -0.12065 -0.2794)
			(end -0.12065 -0.3048)
			(stroke
				(width 0.1)
				(type default)
			)
			(layer "B.Fab")
		)
		(fp_line
			(start 0.12065 0.2794)
			(end 0.12065 0.3048)
			(stroke
				(width 0.1)
				(type default)
			)
			(layer "B.Fab")
		)
		(fp_line
			(start -0.120396 0.2794)
			(end 0.12065 0.2794)
			(stroke
				(width 0.1)
				(type default)
			)
			(layer "B.Fab")
		)
		(fp_line
			(start 0.67945 0.3048)
			(end 0.67945 -0.305054)
			(stroke
				(width 0.1)
				(type default)
			)
			(layer "B.Fab")
		)
		(fp_line
			(start 0.12065 0.3048)
			(end 0.67945 0.3048)
			(stroke
				(width 0.1)
				(type default)
			)
			(layer "B.Fab")
		)
		(fp_line
			(start -0.120396 0.3048)
			(end -0.120396 0.2794)
			(stroke
				(width 0.1)
				(type default)
			)
			(layer "B.Fab")
		)
		(fp_line
			(start -0.67945 0.3048)
			(end -0.120396 0.3048)
			(stroke
				(width 0.1)
				(type default)
			)
			(layer "B.Fab")
		)
		(pad "1" smd circle
			(at 0.40005 0 270)
			(size 0 0)
			(layers "B.Cu" "B.Mask" "B.Paste")
			(net "P0V9_CPU0_RT2_2A")
		)
		(pad "2" smd circle
			(at -0.40005 0 270)
			(size 0 0)
			(layers "B.Cu" "B.Mask" "B.Paste")
			(net "GND")
		)
	)
	(footprint ""
		(layer "B.Cu")
		(at 242.443 -231.648 -90)
		(property "Reference" "R367"
			(at 0 0 90)
			(layer "B.SilkS")
			(hide yes)
			(effects
				(font
					(size 1.27 1.27)
				)
				(justify mirror)
			)
		)
		(property "Value" ""
			(at 0 0 90)
			(layer "B.Fab")
			(effects
				(font
					(size 1.27 1.27)
				)
				(justify mirror)
			)
		)
		(duplicate_pad_numbers_are_jumpers no)
		(fp_line
			(start -0.7874 0.4064)
			(end 0.7874 0.4064)
			(stroke
				(width 0.1524)
				(type default)
			)
			(layer "B.SilkS")
		)
		(fp_line
			(start 0.7874 0.4064)
			(end 0.7874 -0.4064)
			(stroke
				(width 0.1524)
				(type default)
			)
			(layer "B.SilkS")
		)
		(fp_line
			(start -0.7874 -0.4064)
			(end -0.7874 0.4064)
			(stroke
				(width 0.1524)
				(type default)
			)
			(layer "B.SilkS")
		)
		(fp_line
			(start 0.7874 -0.4064)
			(end -0.7874 -0.4064)
			(stroke
				(width 0.1524)
				(type default)
			)
			(layer "B.SilkS")
		)
		(fp_line
			(start -0.67945 0.3048)
			(end -0.120396 0.3048)
			(stroke
				(width 0.1)
				(type default)
			)
			(layer "B.Fab")
		)
		(fp_line
			(start -0.120396 0.3048)
			(end -0.120396 0.2794)
			(stroke
				(width 0.1)
				(type default)
			)
			(layer "B.Fab")
		)
		(fp_line
			(start 0.12065 0.3048)
			(end 0.67945 0.3048)
			(stroke
				(width 0.1)
				(type default)
			)
			(layer "B.Fab")
		)
		(fp_line
			(start 0.67945 0.3048)
			(end 0.67945 -0.305054)
			(stroke
				(width 0.1)
				(type default)
			)
			(layer "B.Fab")
		)
		(fp_line
			(start -0.120396 0.2794)
			(end 0.12065 0.2794)
			(stroke
				(width 0.1)
				(type default)
			)
			(layer "B.Fab")
		)
		(fp_line
			(start 0.12065 0.2794)
			(end 0.12065 0.3048)
			(stroke
				(width 0.1)
				(type default)
			)
			(layer "B.Fab")
		)
		(fp_line
			(start -0.12065 -0.2794)
			(end -0.12065 -0.3048)
			(stroke
				(width 0.1)
				(type default)
			)
			(layer "B.Fab")
		)
		(fp_line
			(start 0.12065 -0.2794)
			(end -0.12065 -0.2794)
			(stroke
				(width 0.1)
				(type default)
			)
			(layer "B.Fab")
		)
		(fp_line
			(start -0.67945 -0.3048)
			(end -0.67945 0.3048)
			(stroke
				(width 0.1)
				(type default)
			)
			(layer "B.Fab")
		)
		(fp_line
			(start -0.12065 -0.3048)
			(end -0.67945 -0.3048)
			(stroke
				(width 0.1)
				(type default)
			)
			(layer "B.Fab")
		)
		(fp_line
			(start 0.12065 -0.305054)
			(end 0.12065 -0.2794)
			(stroke
				(width 0.1)
				(type default)
			)
			(layer "B.Fab")
		)
		(fp_line
			(start 0.67945 -0.305054)
			(end 0.12065 -0.305054)
			(stroke
				(width 0.1)
				(type default)
			)
			(layer "B.Fab")
		)
		(pad "1" smd circle
			(at 0.40005 0 90)
			(size 0 0)
			(layers "B.Cu" "B.Mask" "B.Paste")
			(net "PVDD18_S5_P0")
		)
		(pad "2" smd circle
			(at -0.40005 0 90)
			(size 0 0)
			(layers "B.Cu" "B.Mask" "B.Paste")
			(net "SMB_CPU0_SEC_SCL")
		)
	)
	(footprint ""
		(layer "B.Cu")
		(at 112.611154 -180.200046 90)
		(property "Reference" "PC341_1"
			(at 0 0 90)
			(layer "B.SilkS")
			(hide yes)
			(effects
				(font
					(size 1.27 1.27)
				)
				(justify mirror)
			)
		)
		(property "Value" ""
			(at 0 0 90)
			(layer "B.Fab")
			(effects
				(font
					(size 1.27 1.27)
				)
				(justify mirror)
			)
		)
		(duplicate_pad_numbers_are_jumpers no)
		(fp_line
			(start 1.524 -0.762)
			(end -1.524 -0.762)
			(stroke
				(width 0.1524)
				(type default)
			)
			(layer "B.SilkS")
		)
		(fp_line
			(start -1.524 -0.762)
			(end -1.524 0.762)
			(stroke
				(width 0.1524)
				(type default)
			)
			(layer "B.SilkS")
		)
		(fp_line
			(start 1.524 0.762)
			(end 1.524 -0.762)
			(stroke
				(width 0.1524)
				(type default)
			)
			(layer "B.SilkS")
		)
		(fp_line
			(start -1.524 0.762)
			(end 1.524 0.762)
			(stroke
				(width 0.1524)
				(type default)
			)
			(layer "B.SilkS")
		)
		(fp_line
			(start 1.1049 -0.724916)
			(end 1.1049 0.724916)
			(stroke
				(width 0.1)
				(type default)
			)
			(layer "B.Fab")
		)
		(fp_line
			(start -1.1049 -0.724916)
			(end 1.1049 -0.724916)
			(stroke
				(width 0.1)
				(type default)
			)
			(layer "B.Fab")
		)
		(fp_line
			(start 1.1049 0.724916)
			(end -1.1049 0.724916)
			(stroke
				(width 0.1)
				(type default)
			)
			(layer "B.Fab")
		)
		(fp_line
			(start -1.1049 0.724916)
			(end -1.1049 -0.724916)
			(stroke
				(width 0.1)
				(type default)
			)
			(layer "B.Fab")
		)
		(pad "1" smd rect
			(at 0.889 0 90)
			(size 1.016 1.27)
			(layers "B.Cu" "B.Mask" "B.Paste")
			(net "PVDDCR_SOC_P1")
		)
		(pad "2" smd rect
			(at -0.889 0 90)
			(size 1.016 1.27)
			(layers "B.Cu" "B.Mask" "B.Paste")
			(net "GND")
		)
	)
	(footprint ""
		(layer "B.Cu")
		(at 376.218958 -205.101952 -90)
		(property "Reference" "R398"
			(at 0 0 90)
			(layer "B.SilkS")
			(hide yes)
			(effects
				(font
					(size 1.27 1.27)
				)
				(justify mirror)
			)
		)
		(property "Value" ""
			(at 0 0 90)
			(layer "B.Fab")
			(effects
				(font
					(size 1.27 1.27)
				)
				(justify mirror)
			)
		)
		(duplicate_pad_numbers_are_jumpers no)
		(fp_line
			(start -0.7874 0.4064)
			(end 0.7874 0.4064)
			(stroke
				(width 0.1524)
				(type default)
			)
			(layer "B.SilkS")
		)
		(fp_line
			(start 0.7874 0.4064)
			(end 0.7874 -0.4064)
			(stroke
				(width 0.1524)
				(type default)
			)
			(layer "B.SilkS")
		)
		(fp_line
			(start -0.7874 -0.4064)
			(end -0.7874 0.4064)
			(stroke
				(width 0.1524)
				(type default)
			)
			(layer "B.SilkS")
		)
		(fp_line
			(start 0.7874 -0.4064)
			(end -0.7874 -0.4064)
			(stroke
				(width 0.1524)
				(type default)
			)
			(layer "B.SilkS")
		)
		(fp_line
			(start -0.67945 0.3048)
			(end -0.120396 0.3048)
			(stroke
				(width 0.1)
				(type default)
			)
			(layer "B.Fab")
		)
		(fp_line
			(start -0.120396 0.3048)
			(end -0.120396 0.2794)
			(stroke
				(width 0.1)
				(type default)
			)
			(layer "B.Fab")
		)
		(fp_line
			(start 0.12065 0.3048)
			(end 0.67945 0.3048)
			(stroke
				(width 0.1)
				(type default)
			)
			(layer "B.Fab")
		)
		(fp_line
			(start 0.67945 0.3048)
			(end 0.67945 -0.305054)
			(stroke
				(width 0.1)
				(type default)
			)
			(layer "B.Fab")
		)
		(fp_line
			(start -0.120396 0.2794)
			(end 0.12065 0.2794)
			(stroke
				(width 0.1)
				(type default)
			)
			(layer "B.Fab")
		)
		(fp_line
			(start 0.12065 0.2794)
			(end 0.12065 0.3048)
			(stroke
				(width 0.1)
				(type default)
			)
			(layer "B.Fab")
		)
		(fp_line
			(start -0.12065 -0.2794)
			(end -0.12065 -0.3048)
			(stroke
				(width 0.1)
				(type default)
			)
			(layer "B.Fab")
		)
		(fp_line
			(start 0.12065 -0.2794)
			(end -0.12065 -0.2794)
			(stroke
				(width 0.1)
				(type default)
			)
			(layer "B.Fab")
		)
		(fp_line
			(start -0.67945 -0.3048)
			(end -0.67945 0.3048)
			(stroke
				(width 0.1)
				(type default)
			)
			(layer "B.Fab")
		)
		(fp_line
			(start -0.12065 -0.3048)
			(end -0.67945 -0.3048)
			(stroke
				(width 0.1)
				(type default)
			)
			(layer "B.Fab")
		)
		(fp_line
			(start 0.12065 -0.305054)
			(end 0.12065 -0.2794)
			(stroke
				(width 0.1)
				(type default)
			)
			(layer "B.Fab")
		)
		(fp_line
			(start 0.67945 -0.305054)
			(end 0.12065 -0.305054)
			(stroke
				(width 0.1)
				(type default)
			)
			(layer "B.Fab")
		)
		(pad "1" smd circle
			(at 0.40005 0 90)
			(size 0 0)
			(layers "B.Cu" "B.Mask" "B.Paste")
			(net "PVDD18_S5_P0")
		)
		(pad "2" smd circle
			(at -0.40005 0 90)
			(size 0 0)
			(layers "B.Cu" "B.Mask" "B.Paste")
			(net "JTAG_CPU0_TDO")
		)
	)
	(footprint ""
		(layer "B.Cu")
		(at 112.550448 -171.785534 -90)
		(property "Reference" "PC331_1"
			(at 0 0 90)
			(layer "B.SilkS")
			(hide yes)
			(effects
				(font
					(size 1.27 1.27)
				)
				(justify mirror)
			)
		)
		(property "Value" ""
			(at 0 0 90)
			(layer "B.Fab")
			(effects
				(font
					(size 1.27 1.27)
				)
				(justify mirror)
			)
		)
		(duplicate_pad_numbers_are_jumpers no)
		(fp_line
			(start -1.524 0.762)
			(end 1.524 0.762)
			(stroke
				(width 0.1524)
				(type default)
			)
			(layer "B.SilkS")
		)
		(fp_line
			(start 1.524 0.762)
			(end 1.524 -0.762)
			(stroke
				(width 0.1524)
				(type default)
			)
			(layer "B.SilkS")
		)
		(fp_line
			(start -1.524 -0.762)
			(end -1.524 0.762)
			(stroke
				(width 0.1524)
				(type default)
			)
			(layer "B.SilkS")
		)
		(fp_line
			(start 1.524 -0.762)
			(end -1.524 -0.762)
			(stroke
				(width 0.1524)
				(type default)
			)
			(layer "B.SilkS")
		)
		(fp_line
			(start -1.1049 0.724916)
			(end -1.1049 -0.724916)
			(stroke
				(width 0.1)
				(type default)
			)
			(layer "B.Fab")
		)
		(fp_line
			(start 1.1049 0.724916)
			(end -1.1049 0.724916)
			(stroke
				(width 0.1)
				(type default)
			)
			(layer "B.Fab")
		)
		(fp_line
			(start -1.1049 -0.724916)
			(end 1.1049 -0.724916)
			(stroke
				(width 0.1)
				(type default)
			)
			(layer "B.Fab")
		)
		(fp_line
			(start 1.1049 -0.724916)
			(end 1.1049 0.724916)
			(stroke
				(width 0.1)
				(type default)
			)
			(layer "B.Fab")
		)
		(pad "1" smd rect
			(at 0.889 0 270)
			(size 1.016 1.27)
			(layers "B.Cu" "B.Mask" "B.Paste")
			(net "SW_P12V_AUX_PVDDCR_SOC_P1_FLT")
		)
		(pad "2" smd rect
			(at -0.889 0 270)
			(size 1.016 1.27)
			(layers "B.Cu" "B.Mask" "B.Paste")
			(net "GND")
		)
	)
	(footprint ""
		(layer "B.Cu")
		(at 107.129834 -245.487952 180)
		(property "Reference" "C2308"
			(at 0 0 0)
			(layer "B.SilkS")
			(hide yes)
			(effects
				(font
					(size 1.27 1.27)
				)
				(justify mirror)
			)
		)
		(property "Value" ""
			(at 0 0 0)
			(layer "B.Fab")
			(effects
				(font
					(size 1.27 1.27)
				)
				(justify mirror)
			)
		)
		(duplicate_pad_numbers_are_jumpers no)
		(fp_line
			(start 0.7874 0.4064)
			(end 0.7874 -0.4064)
			(stroke
				(width 0.1524)
				(type default)
			)
			(layer "B.SilkS")
		)
		(fp_line
			(start 0.7874 -0.4064)
			(end -0.7874 -0.4064)
			(stroke
				(width 0.1524)
				(type default)
			)
			(layer "B.SilkS")
		)
		(fp_line
			(start -0.7874 0.4064)
			(end 0.7874 0.4064)
			(stroke
				(width 0.1524)
				(type default)
			)
			(layer "B.SilkS")
		)
		(fp_line
			(start -0.7874 -0.4064)
			(end -0.7874 0.4064)
			(stroke
				(width 0.1524)
				(type default)
			)
			(layer "B.SilkS")
		)
		(fp_line
			(start 0.67945 0.3048)
			(end 0.67945 -0.305054)
			(stroke
				(width 0.1)
				(type default)
			)
			(layer "B.Fab")
		)
		(fp_line
			(start 0.67945 -0.305054)
			(end 0.12065 -0.305054)
			(stroke
				(width 0.1)
				(type default)
			)
			(layer "B.Fab")
		)
		(fp_line
			(start 0.12065 0.3048)
			(end 0.67945 0.3048)
			(stroke
				(width 0.1)
				(type default)
			)
			(layer "B.Fab")
		)
		(fp_line
			(start 0.12065 0.2794)
			(end 0.12065 0.3048)
			(stroke
				(width 0.1)
				(type default)
			)
			(layer "B.Fab")
		)
		(fp_line
			(start 0.12065 -0.2794)
			(end -0.12065 -0.2794)
			(stroke
				(width 0.1)
				(type default)
			)
			(layer "B.Fab")
		)
		(fp_line
			(start 0.12065 -0.305054)
			(end 0.12065 -0.2794)
			(stroke
				(width 0.1)
				(type default)
			)
			(layer "B.Fab")
		)
		(fp_line
			(start -0.120396 0.3048)
			(end -0.120396 0.2794)
			(stroke
				(width 0.1)
				(type default)
			)
			(layer "B.Fab")
		)
		(fp_line
			(start -0.120396 0.2794)
			(end 0.12065 0.2794)
			(stroke
				(width 0.1)
				(type default)
			)
			(layer "B.Fab")
		)
		(fp_line
			(start -0.12065 -0.2794)
			(end -0.12065 -0.3048)
			(stroke
				(width 0.1)
				(type default)
			)
			(layer "B.Fab")
		)
		(fp_line
			(start -0.12065 -0.3048)
			(end -0.67945 -0.3048)
			(stroke
				(width 0.1)
				(type default)
			)
			(layer "B.Fab")
		)
		(fp_line
			(start -0.67945 0.3048)
			(end -0.120396 0.3048)
			(stroke
				(width 0.1)
				(type default)
			)
			(layer "B.Fab")
		)
		(fp_line
			(start -0.67945 -0.3048)
			(end -0.67945 0.3048)
			(stroke
				(width 0.1)
				(type default)
			)
			(layer "B.Fab")
		)
		(pad "1" smd circle
			(at 0.40005 0)
			(size 0 0)
			(layers "B.Cu" "B.Mask" "B.Paste")
			(net "PVDDCR_CPU0_P1")
		)
		(pad "2" smd circle
			(at -0.40005 0)
			(size 0 0)
			(layers "B.Cu" "B.Mask" "B.Paste")
			(net "GND")
		)
	)
	(footprint ""
		(layer "B.Cu")
		(at 123.611386 -259.73024)
		(property "Reference" "C2432"
			(at 0 0 0)
			(layer "B.SilkS")
			(hide yes)
			(effects
				(font
					(size 1.27 1.27)
				)
				(justify mirror)
			)
		)
		(property "Value" ""
			(at 0 0 0)
			(layer "B.Fab")
			(effects
				(font
					(size 1.27 1.27)
				)
				(justify mirror)
			)
		)
		(duplicate_pad_numbers_are_jumpers no)
		(fp_line
			(start -0.7874 -0.4064)
			(end -0.7874 0.4064)
			(stroke
				(width 0.1524)
				(type default)
			)
			(layer "B.SilkS")
		)
		(fp_line
			(start -0.7874 0.4064)
			(end 0.7874 0.4064)
			(stroke
				(width 0.1524)
				(type default)
			)
			(layer "B.SilkS")
		)
		(fp_line
			(start 0.7874 -0.4064)
			(end -0.7874 -0.4064)
			(stroke
				(width 0.1524)
				(type default)
			)
			(layer "B.SilkS")
		)
		(fp_line
			(start 0.7874 0.4064)
			(end 0.7874 -0.4064)
			(stroke
				(width 0.1524)
				(type default)
			)
			(layer "B.SilkS")
		)
		(fp_line
			(start -0.67945 -0.3048)
			(end -0.67945 0.3048)
			(stroke
				(width 0.1)
				(type default)
			)
			(layer "B.Fab")
		)
		(fp_line
			(start -0.67945 0.3048)
			(end -0.120396 0.3048)
			(stroke
				(width 0.1)
				(type default)
			)
			(layer "B.Fab")
		)
		(fp_line
			(start -0.12065 -0.3048)
			(end -0.67945 -0.3048)
			(stroke
				(width 0.1)
				(type default)
			)
			(layer "B.Fab")
		)
		(fp_line
			(start -0.12065 -0.2794)
			(end -0.12065 -0.3048)
			(stroke
				(width 0.1)
				(type default)
			)
			(layer "B.Fab")
		)
		(fp_line
			(start -0.120396 0.2794)
			(end 0.12065 0.2794)
			(stroke
				(width 0.1)
				(type default)
			)
			(layer "B.Fab")
		)
		(fp_line
			(start -0.120396 0.3048)
			(end -0.120396 0.2794)
			(stroke
				(width 0.1)
				(type default)
			)
			(layer "B.Fab")
		)
		(fp_line
			(start 0.12065 -0.305054)
			(end 0.12065 -0.2794)
			(stroke
				(width 0.1)
				(type default)
			)
			(layer "B.Fab")
		)
		(fp_line
			(start 0.12065 -0.2794)
			(end -0.12065 -0.2794)
			(stroke
				(width 0.1)
				(type default)
			)
			(layer "B.Fab")
		)
		(fp_line
			(start 0.12065 0.2794)
			(end 0.12065 0.3048)
			(stroke
				(width 0.1)
				(type default)
			)
			(layer "B.Fab")
		)
		(fp_line
			(start 0.12065 0.3048)
			(end 0.67945 0.3048)
			(stroke
				(width 0.1)
				(type default)
			)
			(layer "B.Fab")
		)
		(fp_line
			(start 0.67945 -0.305054)
			(end 0.12065 -0.305054)
			(stroke
				(width 0.1)
				(type default)
			)
			(layer "B.Fab")
		)
		(fp_line
			(start 0.67945 0.3048)
			(end 0.67945 -0.305054)
			(stroke
				(width 0.1)
				(type default)
			)
			(layer "B.Fab")
		)
		(pad "1" smd circle
			(at 0.40005 0 180)
			(size 0 0)
			(layers "B.Cu" "B.Mask" "B.Paste")
			(net "PVDDCR_SOC_P1")
		)
		(pad "2" smd circle
			(at -0.40005 0 180)
			(size 0 0)
			(layers "B.Cu" "B.Mask" "B.Paste")
			(net "GND")
		)
	)
)
